# T6G (Grand Teton) — schematic netlist excerpt (pin names and nets, part order shuffled) for the footprints in the layout excerpt that follows; sources: Cadence DE-HDL packaged netlist, KiCad conversion of 04192023_DAF0TMB3IC0_F0TG_MB_C_brd_V02_OCP.brd

PC129_6  Q_CAP  22UF 16V 20% X6S  pkg C0805  page 213 : A = SW_P12V_AUX_PVDDCR_CPU0_P1_FLT ; B = GND
PC1750  Q_CAP  33NF 25V 10% EMPTY  pkg C0402  page 266 : A = P12V_AUX ; B = P12V_HSC_GATE2
C2398  Q_CAP  22UF 4V 20% X6S  pkg C0402  page 73 : A = PVDDCR_CPU1_P1 ; B = GND

(kicad_pcb
	(version 20260206)
	(generator "pcbnew")
	(generator_version "10.0")
	(general
		(thickness 1.6)
		(legacy_teardrops no)
	)
	(paper "A4")
	(title_block
		(title "04192023_DAF0TMB3IC0_F0TG_MB_C_brd_V02_OCP.brd")
		(comment 1 "Grand Teton / footprints 5052-5054 of 8354")
	)
	(layers
		(0 "F.Cu" signal "TOP")
		(4 "In1.Cu" signal "GND")
		(6 "In2.Cu" signal "IN1")
		(8 "In3.Cu" signal "GND1")
		(10 "In4.Cu" signal "IN2")
		(12 "In5.Cu" signal "GND2")
		(14 "In6.Cu" signal "IN3")
		(16 "In7.Cu" signal "GND3")
		(18 "In8.Cu" signal "VCC")
		(20 "In9.Cu" signal "VCC1")
		(22 "In10.Cu" signal "GND4")
		(24 "In11.Cu" signal "IN4")
		(26 "In12.Cu" signal "GND5")
		(28 "In13.Cu" signal "IN5")
		(30 "In14.Cu" signal "GND6")
		(32 "In15.Cu" signal "IN6")
		(34 "In16.Cu" signal "GND7")
		(2 "B.Cu" signal "BOTTOM")
		(9 "F.Adhes" user "F.Adhesive")
		(11 "B.Adhes" user "B.Adhesive")
		(13 "F.Paste" user "Package Geometry/Pastemask Top")
		(15 "B.Paste" user "Package Geometry/Pastemask Bottom")
		(5 "F.SilkS" user "Ref Des/Silkscreen Top")
		(7 "B.SilkS" user "Ref Des/Silkscreen Bottom")
		(1 "F.Mask" user "Board Geometry/Soldermask Top")
		(3 "B.Mask" user "Board Geometry/Soldermask Bottom")
		(17 "Dwgs.User" user "User.Drawings")
		(19 "Cmts.User" user "User.Comments")
		(21 "Eco1.User" user "User.Eco1")
		(23 "Eco2.User" user "User.Eco2")
		(25 "Edge.Cuts" user "Board Geometry/Outline")
		(27 "Margin" user)
		(31 "F.CrtYd" user "Package Geometry/Place Bound Top")
		(29 "B.CrtYd" user "Package Geometry/Place Bound Bottom")
		(35 "F.Fab" user "Ref Des/Assembly Top")
		(33 "B.Fab" user "Ref Des/Assembly Bottom")
	)
	(footprint ""
		(layer "B.Cu")
		(at 120.055386 -268.418564)
		(property "Reference" "C2398"
			(at 0 0 0)
			(layer "B.SilkS")
			(hide yes)
			(effects
				(font
					(size 1.27 1.27)
				)
				(justify mirror)
			)
		)
		(property "Value" ""
			(at 0 0 0)
			(layer "B.Fab")
			(effects
				(font
					(size 1.27 1.27)
				)
				(justify mirror)
			)
		)
		(duplicate_pad_numbers_are_jumpers no)
		(fp_line
			(start -0.7874 -0.4064)
			(end -0.7874 0.4064)
			(stroke
				(width 0.1524)
				(type default)
			)
			(layer "B.SilkS")
		)
		(fp_line
			(start -0.7874 0.4064)
			(end 0.7874 0.4064)
			(stroke
				(width 0.1524)
				(type default)
			)
			(layer "B.SilkS")
		)
		(fp_line
			(start 0.7874 -0.4064)
			(end -0.7874 -0.4064)
			(stroke
				(width 0.1524)
				(type default)
			)
			(layer "B.SilkS")
		)
		(fp_line
			(start 0.7874 0.4064)
			(end 0.7874 -0.4064)
			(stroke
				(width 0.1524)
				(type default)
			)
			(layer "B.SilkS")
		)
		(fp_line
			(start -0.67945 -0.3048)
			(end -0.67945 0.3048)
			(stroke
				(width 0.1)
				(type default)
			)
			(layer "B.Fab")
		)
		(fp_line
			(start -0.67945 0.3048)
			(end -0.120396 0.3048)
			(stroke
				(width 0.1)
				(type default)
			)
			(layer "B.Fab")
		)
		(fp_line
			(start -0.12065 -0.3048)
			(end -0.67945 -0.3048)
			(stroke
				(width 0.1)
				(type default)
			)
			(layer "B.Fab")
		)
		(fp_line
			(start -0.12065 -0.2794)
			(end -0.12065 -0.3048)
			(stroke
				(width 0.1)
				(type default)
			)
			(layer "B.Fab")
		)
		(fp_line
			(start -0.120396 0.2794)
			(end 0.12065 0.2794)
			(stroke
				(width 0.1)
				(type default)
			)
			(layer "B.Fab")
		)
		(fp_line
			(start -0.120396 0.3048)
			(end -0.120396 0.2794)
			(stroke
				(width 0.1)
				(type default)
			)
			(layer "B.Fab")
		)
		(fp_line
			(start 0.12065 -0.305054)
			(end 0.12065 -0.2794)
			(stroke
				(width 0.1)
				(type default)
			)
			(layer "B.Fab")
		)
		(fp_line
			(start 0.12065 -0.2794)
			(end -0.12065 -0.2794)
			(stroke
				(width 0.1)
				(type default)
			)
			(layer "B.Fab")
		)
		(fp_line
			(start 0.12065 0.2794)
			(end 0.12065 0.3048)
			(stroke
				(width 0.1)
				(type default)
			)
			(layer "B.Fab")
		)
		(fp_line
			(start 0.12065 0.3048)
			(end 0.67945 0.3048)
			(stroke
				(width 0.1)
				(type default)
			)
			(layer "B.Fab")
		)
		(fp_line
			(start 0.67945 -0.305054)
			(end 0.12065 -0.305054)
			(stroke
				(width 0.1)
				(type default)
			)
			(layer "B.Fab")
		)
		(fp_line
			(start 0.67945 0.3048)
			(end 0.67945 -0.305054)
			(stroke
				(width 0.1)
				(type default)
			)
			(layer "B.Fab")
		)
		(pad "1" smd circle
			(at 0.40005 0 180)
			(size 0 0)
			(layers "B.Cu" "B.Mask" "B.Paste")
			(net "PVDDCR_CPU1_P1")
		)
		(pad "2" smd circle
			(at -0.40005 0 180)
			(size 0 0)
			(layers "B.Cu" "B.Mask" "B.Paste")
			(net "GND")
		)
	)
	(footprint ""
		(layer "B.Cu")
		(at 64.401954 -165.119812 90)
		(property "Reference" "PC129_6"
			(at 0 0 90)
			(layer "B.SilkS")
			(hide yes)
			(effects
				(font
					(size 1.27 1.27)
				)
				(justify mirror)
			)
		)
		(property "Value" ""
			(at 0 0 90)
			(layer "B.Fab")
			(effects
				(font
					(size 1.27 1.27)
				)
				(justify mirror)
			)
		)
		(duplicate_pad_numbers_are_jumpers no)
		(fp_line
			(start 1.524 -0.762)
			(end -1.524 -0.762)
			(stroke
				(width 0.1524)
				(type default)
			)
			(layer "B.SilkS")
		)
		(fp_line
			(start -1.524 -0.762)
			(end -1.524 0.762)
			(stroke
				(width 0.1524)
				(type default)
			)
			(layer "B.SilkS")
		)
		(fp_line
			(start 1.524 0.762)
			(end 1.524 -0.762)
			(stroke
				(width 0.1524)
				(type default)
			)
			(layer "B.SilkS")
		)
		(fp_line
			(start -1.524 0.762)
			(end 1.524 0.762)
			(stroke
				(width 0.1524)
				(type default)
			)
			(layer "B.SilkS")
		)
		(fp_line
			(start 1.1049 -0.724916)
			(end 1.1049 0.724916)
			(stroke
				(width 0.1)
				(type default)
			)
			(layer "B.Fab")
		)
		(fp_line
			(start -1.1049 -0.724916)
			(end 1.1049 -0.724916)
			(stroke
				(width 0.1)
				(type default)
			)
			(layer "B.Fab")
		)
		(fp_line
			(start 1.1049 0.724916)
			(end -1.1049 0.724916)
			(stroke
				(width 0.1)
				(type default)
			)
			(layer "B.Fab")
		)
		(fp_line
			(start -1.1049 0.724916)
			(end -1.1049 -0.724916)
			(stroke
				(width 0.1)
				(type default)
			)
			(layer "B.Fab")
		)
		(pad "1" smd rect
			(at 0.889 0 90)
			(size 1.016 1.27)
			(layers "B.Cu" "B.Mask" "B.Paste")
			(net "SW_P12V_AUX_PVDDCR_CPU0_P1_FLT")
		)
		(pad "2" smd rect
			(at -0.889 0 90)
			(size 1.016 1.27)
			(layers "B.Cu" "B.Mask" "B.Paste")
			(net "GND")
		)
	)
	(footprint ""
		(layer "B.Cu")
		(at 242.702842 -382.467358 180)
		(property "Reference" "PC1750"
			(at 0 0 0)
			(layer "B.SilkS")
			(hide yes)
			(effects
				(font
					(size 1.27 1.27)
				)
				(justify mirror)
			)
		)
		(property "Value" ""
			(at 0 0 0)
			(layer "B.Fab")
			(effects
				(font
					(size 1.27 1.27)
				)
				(justify mirror)
			)
		)
		(duplicate_pad_numbers_are_jumpers no)
		(fp_line
			(start 0.7874 0.4064)
			(end 0.7874 -0.4064)
			(stroke
				(width 0.1524)
				(type default)
			)
			(layer "B.SilkS")
		)
		(fp_line
			(start 0.7874 -0.4064)
			(end -0.7874 -0.4064)
			(stroke
				(width 0.1524)
				(type default)
			)
			(layer "B.SilkS")
		)
		(fp_line
			(start -0.7874 0.4064)
			(end 0.7874 0.4064)
			(stroke
				(width 0.1524)
				(type default)
			)
			(layer "B.SilkS")
		)
		(fp_line
			(start -0.7874 -0.4064)
			(end -0.7874 0.4064)
			(stroke
				(width 0.1524)
				(type default)
			)
			(layer "B.SilkS")
		)
		(fp_line
			(start 0.67945 0.3048)
			(end 0.67945 -0.305054)
			(stroke
				(width 0.1)
				(type default)
			)
			(layer "B.Fab")
		)
		(fp_line
			(start 0.67945 -0.305054)
			(end 0.12065 -0.305054)
			(stroke
				(width 0.1)
				(type default)
			)
			(layer "B.Fab")
		)
		(fp_line
			(start 0.12065 0.3048)
			(end 0.67945 0.3048)
			(stroke
				(width 0.1)
				(type default)
			)
			(layer "B.Fab")
		)
		(fp_line
			(start 0.12065 0.2794)
			(end 0.12065 0.3048)
			(stroke
				(width 0.1)
				(type default)
			)
			(layer "B.Fab")
		)
		(fp_line
			(start 0.12065 -0.2794)
			(end -0.12065 -0.2794)
			(stroke
				(width 0.1)
				(type default)
			)
			(layer "B.Fab")
		)
		(fp_line
			(start 0.12065 -0.305054)
			(end 0.12065 -0.2794)
			(stroke
				(width 0.1)
				(type default)
			)
			(layer "B.Fab")
		)
		(fp_line
			(start -0.120396 0.3048)
			(end -0.120396 0.2794)
			(stroke
				(width 0.1)
				(type default)
			)
			(layer "B.Fab")
		)
		(fp_line
			(start -0.120396 0.2794)
			(end 0.12065 0.2794)
			(stroke
				(width 0.1)
				(type default)
			)
			(layer "B.Fab")
		)
		(fp_line
			(start -0.12065 -0.2794)
			(end -0.12065 -0.3048)
			(stroke
				(width 0.1)
				(type default)
			)
			(layer "B.Fab")
		)
		(fp_line
			(start -0.12065 -0.3048)
			(end -0.67945 -0.3048)
			(stroke
				(width 0.1)
				(type default)
			)
			(layer "B.Fab")
		)
		(fp_line
			(start -0.67945 0.3048)
			(end -0.120396 0.3048)
			(stroke
				(width 0.1)
				(type default)
			)
			(layer "B.Fab")
		)
		(fp_line
			(start -0.67945 -0.3048)
			(end -0.67945 0.3048)
			(stroke
				(width 0.1)
				(type default)
			)
			(layer "B.Fab")
		)
		(pad "1" smd circle
			(at 0.40005 0)
			(size 0 0)
			(layers "B.Cu" "B.Mask" "B.Paste")
			(net "P12V_AUX")
		)
		(pad "2" smd circle
			(at -0.40005 0)
			(size 0 0)
			(layers "B.Cu" "B.Mask" "B.Paste")
			(net "P12V_HSC_GATE2")
		)
	)
)
